# S9S_MB_2U (Grand Teton) — schematic netlist excerpt (pin names and nets, part order shuffled) for the footprints in the layout excerpt that follows; sources: Cadence DE-HDL packaged netlist, KiCad conversion of 03242023_DA0F0TMBIJ0_F0T_Motherboard_J_brd_V01_OCP.brd

PL150  Q_INDUCTOR  300NH/33A IND  pkg SMLF  page 262 : \1\ = SW_P1V05_PCH_AUX_SW ; \2\ = P1V05_PCH_AUX
R3303  Q_RES  0 5% CHIP  pkg 0402LF  page 165 : A = OCP_SFF_PRSNT_ALL_R_N ; B = OCP_SFF_PRSNT_ALL_R1_N
C1592  Q_CAP  0.1UF 25V 10% X7R  pkg 0402  page 191 : A = P3V3_AUX ; B = GND

(kicad_pcb
	(version 20260206)
	(generator "pcbnew")
	(generator_version "10.0")
	(general
		(thickness 1.6)
		(legacy_teardrops no)
	)
	(paper "A4")
	(title_block
		(title "03242023_DA0F0TMBIJ0_F0T_Motherboard_J_brd_V01_OCP.brd")
		(comment 1 "Grand Teton / footprints 704-706 of 6105")
	)
	(layers
		(0 "F.Cu" signal "TOP")
		(4 "In1.Cu" signal "GND")
		(6 "In2.Cu" signal "IN1")
		(8 "In3.Cu" signal "GND1")
		(10 "In4.Cu" signal "IN2")
		(12 "In5.Cu" signal "GND2")
		(14 "In6.Cu" signal "IN3")
		(16 "In7.Cu" signal "GND3")
		(18 "In8.Cu" signal "VCC")
		(20 "In9.Cu" signal "VCC1")
		(22 "In10.Cu" signal "GND4")
		(24 "In11.Cu" signal "IN4")
		(26 "In12.Cu" signal "GND5")
		(28 "In13.Cu" signal "IN5")
		(30 "In14.Cu" signal "GND6")
		(32 "In15.Cu" signal "IN6")
		(34 "In16.Cu" signal "GND7")
		(2 "B.Cu" signal "BOTTOM")
		(9 "F.Adhes" user "F.Adhesive")
		(11 "B.Adhes" user "B.Adhesive")
		(13 "F.Paste" user "Package Geometry/Pastemask Top")
		(15 "B.Paste" user "Package Geometry/Pastemask Bottom")
		(5 "F.SilkS" user "Ref Des/Silkscreen Top")
		(7 "B.SilkS" user "Ref Des/Silkscreen Bottom")
		(1 "F.Mask" user "Board Geometry/Soldermask Top")
		(3 "B.Mask" user "Board Geometry/Soldermask Bottom")
		(17 "Dwgs.User" user "User.Drawings")
		(19 "Cmts.User" user "User.Comments")
		(21 "Eco1.User" user "User.Eco1")
		(23 "Eco2.User" user "User.Eco2")
		(25 "Edge.Cuts" user "Board Geometry/Outline")
		(27 "Margin" user)
		(31 "F.CrtYd" user "Package Geometry/Place Bound Top")
		(29 "B.CrtYd" user "Package Geometry/Place Bound Bottom")
		(35 "F.Fab" user "Ref Des/Assembly Top")
		(33 "B.Fab" user "Ref Des/Assembly Bottom")
	)
	(footprint ""
		(layer "F.Cu")
		(at 147.5359 -40.051736 180)
		(property "Reference" "R3303"
			(at 0 0 180)
			(layer "F.SilkS")
			(hide yes)
			(effects
				(font
					(size 1.27 1.27)
				)
			)
		)
		(property "Value" ""
			(at 0 0 180)
			(layer "F.Fab")
			(effects
				(font
					(size 1.27 1.27)
				)
			)
		)
		(duplicate_pad_numbers_are_jumpers no)
		(fp_line
			(start 0.7874 0.4064)
			(end -0.7874 0.4064)
			(stroke
				(width 0.1524)
				(type default)
			)
			(layer "F.SilkS")
		)
		(fp_line
			(start 0.7874 -0.4064)
			(end 0.7874 0.4064)
			(stroke
				(width 0.1524)
				(type default)
			)
			(layer "F.SilkS")
		)
		(fp_line
			(start -0.7874 0.4064)
			(end -0.7874 -0.4064)
			(stroke
				(width 0.1524)
				(type default)
			)
			(layer "F.SilkS")
		)
		(fp_line
			(start -0.7874 -0.4064)
			(end 0.7874 -0.4064)
			(stroke
				(width 0.1524)
				(type default)
			)
			(layer "F.SilkS")
		)
		(fp_line
			(start 0.67945 0.3048)
			(end 0.120396 0.3048)
			(stroke
				(width 0.1)
				(type default)
			)
			(layer "F.Fab")
		)
		(fp_line
			(start 0.67945 -0.3048)
			(end 0.67945 0.3048)
			(stroke
				(width 0.1)
				(type default)
			)
			(layer "F.Fab")
		)
		(fp_line
			(start 0.12065 -0.2794)
			(end 0.12065 -0.3048)
			(stroke
				(width 0.1)
				(type default)
			)
			(layer "F.Fab")
		)
		(fp_line
			(start 0.12065 -0.3048)
			(end 0.67945 -0.3048)
			(stroke
				(width 0.1)
				(type default)
			)
			(layer "F.Fab")
		)
		(fp_line
			(start 0.120396 0.3048)
			(end 0.120396 0.2794)
			(stroke
				(width 0.1)
				(type default)
			)
			(layer "F.Fab")
		)
		(fp_line
			(start 0.120396 0.2794)
			(end -0.12065 0.2794)
			(stroke
				(width 0.1)
				(type default)
			)
			(layer "F.Fab")
		)
		(fp_line
			(start -0.12065 0.3048)
			(end -0.67945 0.3048)
			(stroke
				(width 0.1)
				(type default)
			)
			(layer "F.Fab")
		)
		(fp_line
			(start -0.12065 0.2794)
			(end -0.12065 0.3048)
			(stroke
				(width 0.1)
				(type default)
			)
			(layer "F.Fab")
		)
		(fp_line
			(start -0.12065 -0.2794)
			(end 0.12065 -0.2794)
			(stroke
				(width 0.1)
				(type default)
			)
			(layer "F.Fab")
		)
		(fp_line
			(start -0.12065 -0.305054)
			(end -0.12065 -0.2794)
			(stroke
				(width 0.1)
				(type default)
			)
			(layer "F.Fab")
		)
		(fp_line
			(start -0.67945 0.3048)
			(end -0.67945 -0.305054)
			(stroke
				(width 0.1)
				(type default)
			)
			(layer "F.Fab")
		)
		(fp_line
			(start -0.67945 -0.305054)
			(end -0.12065 -0.305054)
			(stroke
				(width 0.1)
				(type default)
			)
			(layer "F.Fab")
		)
		(pad "1" smd circle
			(at -0.40005 0 180)
			(size 0 0)
			(layers "F.Cu" "F.Mask" "F.Paste")
			(net "OCP_SFF_PRSNT_ALL_R_N")
		)
		(pad "2" smd circle
			(at 0.40005 0 180)
			(size 0 0)
			(layers "F.Cu" "F.Mask" "F.Paste")
			(net "OCP_SFF_PRSNT_ALL_R1_N")
		)
	)
	(footprint ""
		(layer "F.Cu")
		(at 159.274256 -64.694308 90)
		(property "Reference" "C1592"
			(at 0 0 90)
			(layer "F.SilkS")
			(hide yes)
			(effects
				(font
					(size 1.27 1.27)
				)
			)
		)
		(property "Value" ""
			(at 0 0 90)
			(layer "F.Fab")
			(effects
				(font
					(size 1.27 1.27)
				)
			)
		)
		(duplicate_pad_numbers_are_jumpers no)
		(fp_line
			(start 0.7874 -0.4064)
			(end 0.7874 0.4064)
			(stroke
				(width 0.1524)
				(type default)
			)
			(layer "F.SilkS")
		)
		(fp_line
			(start -0.7874 -0.4064)
			(end 0.7874 -0.4064)
			(stroke
				(width 0.1524)
				(type default)
			)
			(layer "F.SilkS")
		)
		(fp_line
			(start 0.7874 0.4064)
			(end -0.7874 0.4064)
			(stroke
				(width 0.1524)
				(type default)
			)
			(layer "F.SilkS")
		)
		(fp_line
			(start -0.7874 0.4064)
			(end -0.7874 -0.4064)
			(stroke
				(width 0.1524)
				(type default)
			)
			(layer "F.SilkS")
		)
		(fp_line
			(start -0.12065 -0.305054)
			(end -0.12065 -0.2794)
			(stroke
				(width 0.1)
				(type default)
			)
			(layer "F.Fab")
		)
		(fp_line
			(start -0.67945 -0.305054)
			(end -0.12065 -0.305054)
			(stroke
				(width 0.1)
				(type default)
			)
			(layer "F.Fab")
		)
		(fp_line
			(start 0.67945 -0.3048)
			(end 0.67945 0.3048)
			(stroke
				(width 0.1)
				(type default)
			)
			(layer "F.Fab")
		)
		(fp_line
			(start 0.12065 -0.3048)
			(end 0.67945 -0.3048)
			(stroke
				(width 0.1)
				(type default)
			)
			(layer "F.Fab")
		)
		(fp_line
			(start 0.12065 -0.2794)
			(end 0.12065 -0.3048)
			(stroke
				(width 0.1)
				(type default)
			)
			(layer "F.Fab")
		)
		(fp_line
			(start -0.12065 -0.2794)
			(end 0.12065 -0.2794)
			(stroke
				(width 0.1)
				(type default)
			)
			(layer "F.Fab")
		)
		(fp_line
			(start 0.120396 0.2794)
			(end -0.12065 0.2794)
			(stroke
				(width 0.1)
				(type default)
			)
			(layer "F.Fab")
		)
		(fp_line
			(start -0.12065 0.2794)
			(end -0.12065 0.3048)
			(stroke
				(width 0.1)
				(type default)
			)
			(layer "F.Fab")
		)
		(fp_line
			(start 0.67945 0.3048)
			(end 0.120396 0.3048)
			(stroke
				(width 0.1)
				(type default)
			)
			(layer "F.Fab")
		)
		(fp_line
			(start 0.120396 0.3048)
			(end 0.120396 0.2794)
			(stroke
				(width 0.1)
				(type default)
			)
			(layer "F.Fab")
		)
		(fp_line
			(start -0.12065 0.3048)
			(end -0.67945 0.3048)
			(stroke
				(width 0.1)
				(type default)
			)
			(layer "F.Fab")
		)
		(fp_line
			(start -0.67945 0.3048)
			(end -0.67945 -0.305054)
			(stroke
				(width 0.1)
				(type default)
			)
			(layer "F.Fab")
		)
		(pad "1" smd circle
			(at -0.40005 0 90)
			(size 0 0)
			(layers "F.Cu" "F.Mask" "F.Paste")
			(net "P3V3_AUX")
		)
		(pad "2" smd circle
			(at 0.40005 0 90)
			(size 0 0)
			(layers "F.Cu" "F.Mask" "F.Paste")
			(net "GND")
		)
	)
	(footprint ""
		(layer "F.Cu")
		(at 271.225772 -71.4756)
		(property "Reference" "PL150"
			(at -4.800092 -4.062222 0)
			(unlocked yes)
			(layer "F.SilkS")
			(effects
				(font
					(size 0.7874 0.5842)
					(thickness 0.1524)
				)
				(justify left)
			)
		)
		(property "Value" ""
			(at 0 0 0)
			(layer "F.Fab")
			(effects
				(font
					(size 1.27 1.27)
				)
			)
		)
		(duplicate_pad_numbers_are_jumpers no)
		(fp_line
			(start -4.800092 -3.199892)
			(end 4.800092 -3.199892)
			(stroke
				(width 0.1524)
				(type default)
			)
			(layer "F.SilkS")
		)
		(fp_line
			(start -4.800092 -1.6891)
			(end -4.800092 -3.199892)
			(stroke
				(width 0.1524)
				(type default)
			)
			(layer "F.SilkS")
		)
		(fp_line
			(start -4.800092 3.199892)
			(end -4.800092 1.6891)
			(stroke
				(width 0.1524)
				(type default)
			)
			(layer "F.SilkS")
		)
		(fp_line
			(start 4.800092 -3.199892)
			(end 4.800092 -1.6891)
			(stroke
				(width 0.1524)
				(type default)
			)
			(layer "F.SilkS")
		)
		(fp_line
			(start 4.800092 1.6891)
			(end 4.800092 3.199892)
			(stroke
				(width 0.1524)
				(type default)
			)
			(layer "F.SilkS")
		)
		(fp_line
			(start 4.800092 3.199892)
			(end -4.800092 3.199892)
			(stroke
				(width 0.1524)
				(type default)
			)
			(layer "F.SilkS")
		)
		(fp_line
			(start -4.800092 -3.199892)
			(end 4.800092 -3.199892)
			(stroke
				(width 0.1)
				(type default)
			)
			(layer "F.Fab")
		)
		(fp_line
			(start -4.800092 3.199892)
			(end -4.800092 -3.199892)
			(stroke
				(width 0.1)
				(type default)
			)
			(layer "F.Fab")
		)
		(fp_line
			(start 4.800092 -3.199892)
			(end 4.800092 3.199892)
			(stroke
				(width 0.1)
				(type default)
			)
			(layer "F.Fab")
		)
		(fp_line
			(start 4.800092 3.199892)
			(end -4.800092 3.199892)
			(stroke
				(width 0.1)
				(type default)
			)
			(layer "F.Fab")
		)
		(pad "1" smd rect
			(at -3.350006 0 90)
			(size 3.0988 3.2004)
			(layers "F.Cu" "F.Mask" "F.Paste")
			(net "SW_P1V05_PCH_AUX_SW")
		)
		(pad "2" smd rect
			(at 3.350006 0 90)
			(size 3.0988 3.2004)
			(layers "F.Cu" "F.Mask" "F.Paste")
			(net "P1V05_PCH_AUX")
		)
	)
)
